FILE_TYPE = CONNECTIVITY;
{Allegro Design Entry HDL 17.2-2016 S081 (4005846) 1/11/2022}
"PAGE_NUMBER" = 40;
0"NC";
1"PVCCA_AUX_PLD\g";
2"GND\g";
%"LCMXO3LF2100C5BG256C"
"7","(-4750,4425)","0","pure_quanta","I1";
;
PART_NUMBER"AJ021000T03"
MATERIAL"IC"
PART_TYPE"SMLF"
VALUE"LCMXO3LF-2100C-5BG256C"
CDS_LIB"pure_quanta"
NEEDS_NO_SIZE"TRUE"
CDS_LMAN_SYM_OUTLINE"-450,700,450,-700"
LOCATION"U25"
$SEC"7"
CDS_SEC"7";
"VCC_A1"
$PN"A1"1;
"VCC_A16"
$PN"A16"1;
"VCC_G7"
$PN"G7"1;
"VCC_G10"
$PN"G10"1;
"VCC_K7"
$PN"K7"1;
"VCC_K10"
$PN"K10"1;
"VCC_T1"
$PN"T1"1;
"VCC_T16"
$PN"T16"1;
"NC1"
$PN"A2"0;
"GND_R15"
$PN"R15"2;
"GND_R2"
$PN"R2"2;
"GND_P14"
$PN"P14"2;
"GND_P3"
$PN"P3"2;
"GND_N13"
$PN"N13"2;
"GND_N4"
$PN"N4"2;
"GND_M12"
$PN"M12"2;
"GND_M5"
$PN"M5"2;
"GND_L11"
$PN"L11"2;
"GND_L6"
$PN"L6"2;
"GND_J9"
$PN"J9"2;
"GND_J8"
$PN"J8"2;
"GND_H9"
$PN"H9"2;
"GND_H8"
$PN"H8"2;
"GND_F11"
$PN"F11"2;
"GND_F6"
$PN"F6"2;
"GND_E12"
$PN"E12"2;
"GND_E5"
$PN"E5"2;
"GND_D13"
$PN"D13"2;
"GND_D4"
$PN"D4"2;
"GND_C14"
$PN"C14"2;
"GND_C3"
$PN"C3"2;
"GND_B15"
$PN"B15"2;
"GND_B2"
$PN"B2"2;
%"UNIVERSAL_GND"
"1","(-5550,3300)","0","logical_power","I2";
;
HDL_POWER"GND"
CDS_LIB"logical_power";
"A"2;
%"UNIVERSAL_POWER"
"1","(-3950,5275)","0","logical_power","I3";
;
HDL_POWER"PVCCA_AUX_PLD"
CDS_LIB"logical_power";
"A"1;
END.
